# T6G (Grand Teton) — schematic netlist excerpt (pin names and nets, part order shuffled) for the footprints in the layout excerpt that follows; sources: Cadence DE-HDL packaged netlist, KiCad conversion of 04192023_DAF0TMB3IC0_F0TG_MB_C_brd_V02_OCP.brd

R3172  Q_RES  0 5% CHIP  pkg 0402LF  page 137 : A = OCP_V3_2_AUX_PWR_EN ; B = OCP_V3_2_AUX_PWR_EN_R
R615  Q_RES  0 5% CHIP  pkg 0201LF  page 309 : A = CLK_100M_RETIMER_CPU0_P3_R_DP ; B = CLK_100M_RETIMER_CPU0_P3_DP
R77  Q_RES  100K 1% CHIP  pkg 0402LF  page 132 : A = RMII_OCP_BMC_CRSDV ; B = GND

(kicad_pcb
	(version 20260206)
	(generator "pcbnew")
	(generator_version "10.0")
	(general
		(thickness 1.6)
		(legacy_teardrops no)
	)
	(paper "A4")
	(title_block
		(title "04192023_DAF0TMB3IC0_F0TG_MB_C_brd_V02_OCP.brd")
		(comment 1 "Grand Teton / footprints 1269-1271 of 8354")
	)
	(layers
		(0 "F.Cu" signal "TOP")
		(4 "In1.Cu" signal "GND")
		(6 "In2.Cu" signal "IN1")
		(8 "In3.Cu" signal "GND1")
		(10 "In4.Cu" signal "IN2")
		(12 "In5.Cu" signal "GND2")
		(14 "In6.Cu" signal "IN3")
		(16 "In7.Cu" signal "GND3")
		(18 "In8.Cu" signal "VCC")
		(20 "In9.Cu" signal "VCC1")
		(22 "In10.Cu" signal "GND4")
		(24 "In11.Cu" signal "IN4")
		(26 "In12.Cu" signal "GND5")
		(28 "In13.Cu" signal "IN5")
		(30 "In14.Cu" signal "GND6")
		(32 "In15.Cu" signal "IN6")
		(34 "In16.Cu" signal "GND7")
		(2 "B.Cu" signal "BOTTOM")
		(9 "F.Adhes" user "F.Adhesive")
		(11 "B.Adhes" user "B.Adhesive")
		(13 "F.Paste" user "Package Geometry/Pastemask Top")
		(15 "B.Paste" user "Package Geometry/Pastemask Bottom")
		(5 "F.SilkS" user "Ref Des/Silkscreen Top")
		(7 "B.SilkS" user "Ref Des/Silkscreen Bottom")
		(1 "F.Mask" user "Board Geometry/Soldermask Top")
		(3 "B.Mask" user "Board Geometry/Soldermask Bottom")
		(17 "Dwgs.User" user "User.Drawings")
		(19 "Cmts.User" user "User.Comments")
		(21 "Eco1.User" user "User.Eco1")
		(23 "Eco2.User" user "User.Eco2")
		(25 "Edge.Cuts" user "Board Geometry/Outline")
		(27 "Margin" user)
		(31 "F.CrtYd" user "Package Geometry/Place Bound Top")
		(29 "B.CrtYd" user "Package Geometry/Place Bound Bottom")
		(35 "F.Fab" user "Ref Des/Assembly Top")
		(33 "B.Fab" user "Ref Des/Assembly Bottom")
	)
	(footprint ""
		(layer "F.Cu")
		(at 365.62792 -396.146274)
		(property "Reference" "R615"
			(at 0 0 0)
			(layer "F.SilkS")
			(hide yes)
			(effects
				(font
					(size 1.27 1.27)
				)
			)
		)
		(property "Value" ""
			(at 0 0 0)
			(layer "F.Fab")
			(effects
				(font
					(size 1.27 1.27)
				)
			)
		)
		(duplicate_pad_numbers_are_jumpers no)
		(fp_line
			(start -0.32512 -0.175006)
			(end 0.32512 -0.175006)
			(stroke
				(width 0.1)
				(type default)
			)
			(layer "F.Fab")
		)
		(fp_line
			(start -0.32512 0.175006)
			(end -0.32512 -0.175006)
			(stroke
				(width 0.1)
				(type default)
			)
			(layer "F.Fab")
		)
		(fp_line
			(start 0.32512 -0.175006)
			(end 0.32512 0.175006)
			(stroke
				(width 0.1)
				(type default)
			)
			(layer "F.Fab")
		)
		(fp_line
			(start 0.32512 0.175006)
			(end -0.32512 0.175006)
			(stroke
				(width 0.1)
				(type default)
			)
			(layer "F.Fab")
		)
		(pad "1" smd rect
			(at -0.2667 0)
			(size 0.3048 0.381)
			(layers "F.Cu" "F.Mask" "F.Paste")
			(net "CLK_100M_RETIMER_CPU0_P3_R_DP")
		)
		(pad "2" smd rect
			(at 0.2667 0 180)
			(size 0.3048 0.381)
			(layers "F.Cu" "F.Mask" "F.Paste")
			(net "CLK_100M_RETIMER_CPU0_P3_DP")
		)
	)
	(footprint ""
		(layer "F.Cu")
		(at 60.011564 -16.220948 -90)
		(property "Reference" "R3172"
			(at 0 0 270)
			(layer "F.SilkS")
			(hide yes)
			(effects
				(font
					(size 1.27 1.27)
				)
			)
		)
		(property "Value" ""
			(at 0 0 270)
			(layer "F.Fab")
			(effects
				(font
					(size 1.27 1.27)
				)
			)
		)
		(duplicate_pad_numbers_are_jumpers no)
		(fp_line
			(start -0.7874 0.4064)
			(end -0.7874 -0.4064)
			(stroke
				(width 0.1524)
				(type default)
			)
			(layer "F.SilkS")
		)
		(fp_line
			(start 0.7874 0.4064)
			(end -0.7874 0.4064)
			(stroke
				(width 0.1524)
				(type default)
			)
			(layer "F.SilkS")
		)
		(fp_line
			(start -0.7874 -0.4064)
			(end 0.7874 -0.4064)
			(stroke
				(width 0.1524)
				(type default)
			)
			(layer "F.SilkS")
		)
		(fp_line
			(start 0.7874 -0.4064)
			(end 0.7874 0.4064)
			(stroke
				(width 0.1524)
				(type default)
			)
			(layer "F.SilkS")
		)
		(fp_line
			(start -0.67945 0.3048)
			(end -0.67945 -0.305054)
			(stroke
				(width 0.1)
				(type default)
			)
			(layer "F.Fab")
		)
		(fp_line
			(start -0.12065 0.3048)
			(end -0.67945 0.3048)
			(stroke
				(width 0.1)
				(type default)
			)
			(layer "F.Fab")
		)
		(fp_line
			(start 0.120396 0.3048)
			(end 0.120396 0.2794)
			(stroke
				(width 0.1)
				(type default)
			)
			(layer "F.Fab")
		)
		(fp_line
			(start 0.67945 0.3048)
			(end 0.120396 0.3048)
			(stroke
				(width 0.1)
				(type default)
			)
			(layer "F.Fab")
		)
		(fp_line
			(start -0.12065 0.2794)
			(end -0.12065 0.3048)
			(stroke
				(width 0.1)
				(type default)
			)
			(layer "F.Fab")
		)
		(fp_line
			(start 0.120396 0.2794)
			(end -0.12065 0.2794)
			(stroke
				(width 0.1)
				(type default)
			)
			(layer "F.Fab")
		)
		(fp_line
			(start -0.12065 -0.2794)
			(end 0.12065 -0.2794)
			(stroke
				(width 0.1)
				(type default)
			)
			(layer "F.Fab")
		)
		(fp_line
			(start 0.12065 -0.2794)
			(end 0.12065 -0.3048)
			(stroke
				(width 0.1)
				(type default)
			)
			(layer "F.Fab")
		)
		(fp_line
			(start 0.12065 -0.3048)
			(end 0.67945 -0.3048)
			(stroke
				(width 0.1)
				(type default)
			)
			(layer "F.Fab")
		)
		(fp_line
			(start 0.67945 -0.3048)
			(end 0.67945 0.3048)
			(stroke
				(width 0.1)
				(type default)
			)
			(layer "F.Fab")
		)
		(fp_line
			(start -0.67945 -0.305054)
			(end -0.12065 -0.305054)
			(stroke
				(width 0.1)
				(type default)
			)
			(layer "F.Fab")
		)
		(fp_line
			(start -0.12065 -0.305054)
			(end -0.12065 -0.2794)
			(stroke
				(width 0.1)
				(type default)
			)
			(layer "F.Fab")
		)
		(pad "1" smd circle
			(at -0.40005 0 270)
			(size 0 0)
			(layers "F.Cu" "F.Mask" "F.Paste")
			(net "OCP_V3_2_AUX_PWR_EN")
		)
		(pad "2" smd circle
			(at 0.40005 0 270)
			(size 0 0)
			(layers "F.Cu" "F.Mask" "F.Paste")
			(net "OCP_V3_2_AUX_PWR_EN_R")
		)
	)
	(footprint ""
		(layer "F.Cu")
		(at 197.876922 -76.016866)
		(property "Reference" "R77"
			(at 0 0 0)
			(layer "F.SilkS")
			(hide yes)
			(effects
				(font
					(size 1.27 1.27)
				)
			)
		)
		(property "Value" ""
			(at 0 0 0)
			(layer "F.Fab")
			(effects
				(font
					(size 1.27 1.27)
				)
			)
		)
		(duplicate_pad_numbers_are_jumpers no)
		(fp_line
			(start -0.7874 -0.4064)
			(end 0.7874 -0.4064)
			(stroke
				(width 0.1524)
				(type default)
			)
			(layer "F.SilkS")
		)
		(fp_line
			(start -0.7874 0.4064)
			(end -0.7874 -0.4064)
			(stroke
				(width 0.1524)
				(type default)
			)
			(layer "F.SilkS")
		)
		(fp_line
			(start 0.7874 -0.4064)
			(end 0.7874 0.4064)
			(stroke
				(width 0.1524)
				(type default)
			)
			(layer "F.SilkS")
		)
		(fp_line
			(start 0.7874 0.4064)
			(end -0.7874 0.4064)
			(stroke
				(width 0.1524)
				(type default)
			)
			(layer "F.SilkS")
		)
		(fp_line
			(start -0.67945 -0.305054)
			(end -0.12065 -0.305054)
			(stroke
				(width 0.1)
				(type default)
			)
			(layer "F.Fab")
		)
		(fp_line
			(start -0.67945 0.3048)
			(end -0.67945 -0.305054)
			(stroke
				(width 0.1)
				(type default)
			)
			(layer "F.Fab")
		)
		(fp_line
			(start -0.12065 -0.305054)
			(end -0.12065 -0.2794)
			(stroke
				(width 0.1)
				(type default)
			)
			(layer "F.Fab")
		)
		(fp_line
			(start -0.12065 -0.2794)
			(end 0.12065 -0.2794)
			(stroke
				(width 0.1)
				(type default)
			)
			(layer "F.Fab")
		)
		(fp_line
			(start -0.12065 0.2794)
			(end -0.12065 0.3048)
			(stroke
				(width 0.1)
				(type default)
			)
			(layer "F.Fab")
		)
		(fp_line
			(start -0.12065 0.3048)
			(end -0.67945 0.3048)
			(stroke
				(width 0.1)
				(type default)
			)
			(layer "F.Fab")
		)
		(fp_line
			(start 0.120396 0.2794)
			(end -0.12065 0.2794)
			(stroke
				(width 0.1)
				(type default)
			)
			(layer "F.Fab")
		)
		(fp_line
			(start 0.120396 0.3048)
			(end 0.120396 0.2794)
			(stroke
				(width 0.1)
				(type default)
			)
			(layer "F.Fab")
		)
		(fp_line
			(start 0.12065 -0.3048)
			(end 0.67945 -0.3048)
			(stroke
				(width 0.1)
				(type default)
			)
			(layer "F.Fab")
		)
		(fp_line
			(start 0.12065 -0.2794)
			(end 0.12065 -0.3048)
			(stroke
				(width 0.1)
				(type default)
			)
			(layer "F.Fab")
		)
		(fp_line
			(start 0.67945 -0.3048)
			(end 0.67945 0.3048)
			(stroke
				(width 0.1)
				(type default)
			)
			(layer "F.Fab")
		)
		(fp_line
			(start 0.67945 0.3048)
			(end 0.120396 0.3048)
			(stroke
				(width 0.1)
				(type default)
			)
			(layer "F.Fab")
		)
		(pad "1" smd circle
			(at -0.40005 0)
			(size 0 0)
			(layers "F.Cu" "F.Mask" "F.Paste")
			(net "RMII_OCP_BMC_CRSDV")
		)
		(pad "2" smd circle
			(at 0.40005 0)
			(size 0 0)
			(layers "F.Cu" "F.Mask" "F.Paste")
			(net "GND")
		)
	)
)
